# S9S_MB_2U (Grand Teton) — schematic netlist excerpt (pin names and nets, part order shuffled) for the footprints in the layout excerpt that follows; sources: Cadence DE-HDL packaged netlist, KiCad conversion of 03242023_DA0F0TMBIJ0_F0T_Motherboard_J_brd_V01_OCP.brd

U158  MOSFET_NCH_GDS_ESD_PROTECTED  2N7002K IC  pkg SOT23_GDSXC  page 247
  D  = FM_P12V_HSC_EN_N
  G  = FM_P12V_HSC_EN_R
  S  = GND

Q152  MOSFET_NCH_DUAL  PJT138K IC  pkg SOT363XD  page 144
  S1  = GND
  G1  = PRSNT_CABLE_SWB_B2_N
  D2  = PRSNT_CABLE_SWB_B2_ISO_N
  S2  = GND
  G2  = PRSNT_CABLE_SWB_B2
  D1  = PRSNT_CABLE_SWB_B2

(kicad_pcb
	(version 20260206)
	(generator "pcbnew")
	(generator_version "10.0")
	(general
		(thickness 1.6)
		(legacy_teardrops no)
	)
	(paper "A4")
	(title_block
		(title "03242023_DA0F0TMBIJ0_F0T_Motherboard_J_brd_V01_OCP.brd")
		(comment 1 "Grand Teton / footprints 1456-1457 of 6105")
	)
	(layers
		(0 "F.Cu" signal "TOP")
		(4 "In1.Cu" signal "GND")
		(6 "In2.Cu" signal "IN1")
		(8 "In3.Cu" signal "GND1")
		(10 "In4.Cu" signal "IN2")
		(12 "In5.Cu" signal "GND2")
		(14 "In6.Cu" signal "IN3")
		(16 "In7.Cu" signal "GND3")
		(18 "In8.Cu" signal "VCC")
		(20 "In9.Cu" signal "VCC1")
		(22 "In10.Cu" signal "GND4")
		(24 "In11.Cu" signal "IN4")
		(26 "In12.Cu" signal "GND5")
		(28 "In13.Cu" signal "IN5")
		(30 "In14.Cu" signal "GND6")
		(32 "In15.Cu" signal "IN6")
		(34 "In16.Cu" signal "GND7")
		(2 "B.Cu" signal "BOTTOM")
		(9 "F.Adhes" user "F.Adhesive")
		(11 "B.Adhes" user "B.Adhesive")
		(13 "F.Paste" user "Package Geometry/Pastemask Top")
		(15 "B.Paste" user "Package Geometry/Pastemask Bottom")
		(5 "F.SilkS" user "Ref Des/Silkscreen Top")
		(7 "B.SilkS" user "Ref Des/Silkscreen Bottom")
		(1 "F.Mask" user "Board Geometry/Soldermask Top")
		(3 "B.Mask" user "Board Geometry/Soldermask Bottom")
		(17 "Dwgs.User" user "User.Drawings")
		(19 "Cmts.User" user "User.Comments")
		(21 "Eco1.User" user "User.Eco1")
		(23 "Eco2.User" user "User.Eco2")
		(25 "Edge.Cuts" user "Board Geometry/Outline")
		(27 "Margin" user)
		(31 "F.CrtYd" user "Package Geometry/Place Bound Top")
		(29 "B.CrtYd" user "Package Geometry/Place Bound Bottom")
		(35 "F.Fab" user "Ref Des/Assembly Top")
		(33 "B.Fab" user "Ref Des/Assembly Bottom")
	)
	(footprint ""
		(layer "F.Cu")
		(at 202.59802 -128.516888 180)
		(property "Reference" "U158"
			(at 1.68402 -2.72161 0)
			(unlocked yes)
			(layer "F.SilkS")
			(effects
				(font
					(size 0.7874 0.5842)
					(thickness 0.1524)
				)
				(justify left)
			)
		)
		(property "Value" ""
			(at 0 0 180)
			(layer "F.Fab")
			(effects
				(font
					(size 1.27 1.27)
				)
			)
		)
		(duplicate_pad_numbers_are_jumpers no)
		(fp_line
			(start 1.603248 1.500124)
			(end -1.603248 1.500124)
			(stroke
				(width 0.1524)
				(type default)
			)
			(layer "F.SilkS")
		)
		(fp_line
			(start 1.603248 -1.500124)
			(end 1.603248 1.500124)
			(stroke
				(width 0.1524)
				(type default)
			)
			(layer "F.SilkS")
		)
		(fp_line
			(start -1.603248 1.500124)
			(end -1.603248 -1.500124)
			(stroke
				(width 0.1524)
				(type default)
			)
			(layer "F.SilkS")
		)
		(fp_line
			(start -1.603248 -1.500124)
			(end 1.603248 -1.500124)
			(stroke
				(width 0.1524)
				(type default)
			)
			(layer "F.SilkS")
		)
		(fp_line
			(start 1.249934 0.219964)
			(end 1.249934 -0.219964)
			(stroke
				(width 0.1)
				(type default)
			)
			(layer "F.Fab")
		)
		(fp_line
			(start 1.249934 -0.219964)
			(end 0.700024 -0.219964)
			(stroke
				(width 0.1)
				(type default)
			)
			(layer "F.Fab")
		)
		(fp_line
			(start 0.700024 1.500124)
			(end 0.700024 0.219964)
			(stroke
				(width 0.1)
				(type default)
			)
			(layer "F.Fab")
		)
		(fp_line
			(start 0.700024 0.219964)
			(end 1.249934 0.219964)
			(stroke
				(width 0.1)
				(type default)
			)
			(layer "F.Fab")
		)
		(fp_line
			(start 0.700024 -0.219964)
			(end 0.700024 -1.500124)
			(stroke
				(width 0.1)
				(type default)
			)
			(layer "F.Fab")
		)
		(fp_line
			(start 0.700024 -1.500124)
			(end -0.700024 -1.500124)
			(stroke
				(width 0.1)
				(type default)
			)
			(layer "F.Fab")
		)
		(fp_line
			(start -0.6985 0.729996)
			(end -1.249934 0.729996)
			(stroke
				(width 0.1)
				(type default)
			)
			(layer "F.Fab")
		)
		(fp_line
			(start -0.6985 -0.729996)
			(end -0.6985 0.729996)
			(stroke
				(width 0.1)
				(type default)
			)
			(layer "F.Fab")
		)
		(fp_line
			(start -0.700024 1.500124)
			(end 0.700024 1.500124)
			(stroke
				(width 0.1)
				(type default)
			)
			(layer "F.Fab")
		)
		(fp_line
			(start -0.700024 1.169924)
			(end -0.700024 1.500124)
			(stroke
				(width 0.1)
				(type default)
			)
			(layer "F.Fab")
		)
		(fp_line
			(start -0.700024 -1.169924)
			(end -1.249934 -1.169924)
			(stroke
				(width 0.1)
				(type default)
			)
			(layer "F.Fab")
		)
		(fp_line
			(start -0.700024 -1.500124)
			(end -0.700024 -1.169924)
			(stroke
				(width 0.1)
				(type default)
			)
			(layer "F.Fab")
		)
		(fp_line
			(start -1.249934 1.169924)
			(end -0.700024 1.169924)
			(stroke
				(width 0.1)
				(type default)
			)
			(layer "F.Fab")
		)
		(fp_line
			(start -1.249934 0.729996)
			(end -1.249934 1.169924)
			(stroke
				(width 0.1)
				(type default)
			)
			(layer "F.Fab")
		)
		(fp_line
			(start -1.249934 -0.729996)
			(end -0.6985 -0.729996)
			(stroke
				(width 0.1)
				(type default)
			)
			(layer "F.Fab")
		)
		(fp_line
			(start -1.249934 -1.169924)
			(end -1.249934 -0.729996)
			(stroke
				(width 0.1)
				(type default)
			)
			(layer "F.Fab")
		)
		(fp_rect
			(start -0.700024 -1.500124)
			(end 0.700024 1.500124)
			(stroke
				(width 0)
				(type default)
			)
			(fill no)
			(layer "F.Fab")
		)
		(pad "D" smd rect
			(at 0.999998 0 90)
			(size 0.8128 0.9144)
			(layers "F.Cu" "F.Mask" "F.Paste")
			(net "FM_P12V_HSC_EN_N")
		)
		(pad "G" smd rect
			(at -0.999998 -0.94996 90)
			(size 0.8128 0.9144)
			(layers "F.Cu" "F.Mask" "F.Paste")
			(net "FM_P12V_HSC_EN_R")
		)
		(pad "S" smd rect
			(at -0.999998 0.94996 90)
			(size 0.8128 0.9144)
			(layers "F.Cu" "F.Mask" "F.Paste")
			(net "GND")
		)
	)
	(footprint ""
		(layer "F.Cu")
		(at 358.648 -402.844)
		(property "Reference" "Q152"
			(at 0.23876 1.764792 0)
			(unlocked yes)
			(layer "F.SilkS")
			(effects
				(font
					(size 0.7874 0.5842)
					(thickness 0.1524)
				)
				(justify left)
			)
		)
		(property "Value" ""
			(at 0 0 0)
			(layer "F.Fab")
			(effects
				(font
					(size 1.27 1.27)
				)
			)
		)
		(duplicate_pad_numbers_are_jumpers no)
		(fp_line
			(start -1.332738 -1.100074)
			(end -0.4826 -1.100074)
			(stroke
				(width 0.1524)
				(type default)
			)
			(layer "F.SilkS")
		)
		(fp_line
			(start -1.332738 1.100074)
			(end -1.332738 -1.100074)
			(stroke
				(width 0.1524)
				(type default)
			)
			(layer "F.SilkS")
		)
		(fp_line
			(start -0.4826 -1.100074)
			(end 0 -0.541274)
			(stroke
				(width 0.1524)
				(type default)
			)
			(layer "F.SilkS")
		)
		(fp_line
			(start 0 -0.541274)
			(end 0.4826 -1.100074)
			(stroke
				(width 0.1524)
				(type default)
			)
			(layer "F.SilkS")
		)
		(fp_line
			(start 0.4826 -1.100074)
			(end 1.332738 -1.100074)
			(stroke
				(width 0.1524)
				(type default)
			)
			(layer "F.SilkS")
		)
		(fp_line
			(start 1.332738 -1.100074)
			(end 1.332738 1.100074)
			(stroke
				(width 0.1524)
				(type default)
			)
			(layer "F.SilkS")
		)
		(fp_line
			(start 1.332738 1.100074)
			(end -1.332738 1.100074)
			(stroke
				(width 0.1524)
				(type default)
			)
			(layer "F.SilkS")
		)
		(fp_poly
			(pts
				(xy -1.921764 -1.517396) (xy -1.425194 -2.013966) (xy -1.177036 -1.269238)
			)
			(stroke
				(width 0)
				(type default)
			)
			(fill yes)
			(layer "F.SilkS")
		)
		(fp_line
			(start -0.674878 -1.100074)
			(end 0.674878 -1.100074)
			(stroke
				(width 0.1)
				(type default)
			)
			(layer "F.Fab")
		)
		(fp_line
			(start -0.674878 1.100074)
			(end -0.674878 -1.100074)
			(stroke
				(width 0.1)
				(type default)
			)
			(layer "F.Fab")
		)
		(fp_line
			(start 0.674878 -1.100074)
			(end 0.674878 1.100074)
			(stroke
				(width 0.1)
				(type default)
			)
			(layer "F.Fab")
		)
		(fp_line
			(start 0.674878 1.100074)
			(end -0.674878 1.100074)
			(stroke
				(width 0.1)
				(type default)
			)
			(layer "F.Fab")
		)
		(fp_poly
			(pts
				(xy -2.2352 -0.298958) (xy -2.2352 -1.001014) (xy -1.533144 -0.649986)
			)
			(stroke
				(width 0)
				(type default)
			)
			(fill yes)
			(layer "F.Fab")
		)
		(pad "1" smd rect
			(at -0.94996 -0.649986 90)
			(size 0.4318 0.508)
			(layers "F.Cu" "F.Mask" "F.Paste")
			(net "GND")
		)
		(pad "2" smd rect
			(at -0.94996 0 90)
			(size 0.4318 0.508)
			(layers "F.Cu" "F.Mask" "F.Paste")
			(net "PRSNT_CABLE_SWB_B2_N")
		)
		(pad "3" smd rect
			(at -0.94996 0.649986 90)
			(size 0.4318 0.508)
			(layers "F.Cu" "F.Mask" "F.Paste")
			(net "PRSNT_CABLE_SWB_B2_ISO_N")
		)
		(pad "4" smd rect
			(at 0.94996 0.649986 90)
			(size 0.4318 0.508)
			(layers "F.Cu" "F.Mask" "F.Paste")
			(net "GND")
		)
		(pad "5" smd rect
			(at 0.94996 0 90)
			(size 0.4318 0.508)
			(layers "F.Cu" "F.Mask" "F.Paste")
			(net "PRSNT_CABLE_SWB_B2")
		)
		(pad "6" smd rect
			(at 0.94996 -0.649986 90)
			(size 0.4318 0.508)
			(layers "F.Cu" "F.Mask" "F.Paste")
			(net "PRSNT_CABLE_SWB_B2")
		)
	)
)
